(kicad_pcb
	(version 20260206)
	(generator "pcbnew")
	(generator_version "10.0")
	(general
		(thickness 1.6)
		(legacy_teardrops no)
	)
	(paper "A4")
	(title_block
		(title "12092022_DA0F0TMDCD0_F0T_Management_Board_D_brd_V3_OCP.brd")
		(comment 1 "Grand Teton / footprints 727-732 of 1440")
	)
	(layers
		(0 "F.Cu" signal "TOP")
		(4 "In1.Cu" signal "GND")
		(6 "In2.Cu" signal "IN1")
		(8 "In3.Cu" signal "GND1")
		(10 "In4.Cu" signal "IN2")
		(12 "In5.Cu" signal "VCC")
		(14 "In6.Cu" signal "VCC1")
		(16 "In7.Cu" signal "IN3")
		(18 "In8.Cu" signal "GND2")
		(20 "In9.Cu" signal "IN4")
		(22 "In10.Cu" signal "GND3")
		(2 "B.Cu" signal "BOTTOM")
		(9 "F.Adhes" user "F.Adhesive")
		(11 "B.Adhes" user "B.Adhesive")
		(13 "F.Paste" user "Package Geometry/Pastemask Top")
		(15 "B.Paste" user "Package Geometry/Pastemask Bottom")
		(5 "F.SilkS" user "Ref Des/Silkscreen Top")
		(7 "B.SilkS" user "Ref Des/Silkscreen Bottom")
		(1 "F.Mask" user "Board Geometry/Soldermask Top")
		(3 "B.Mask" user "Board Geometry/Soldermask Bottom")
		(17 "Dwgs.User" user "User.Drawings")
		(19 "Cmts.User" user "User.Comments")
		(21 "Eco1.User" user "User.Eco1")
		(23 "Eco2.User" user "User.Eco2")
		(25 "Edge.Cuts" user "Board Geometry/Outline")
		(27 "Margin" user)
		(31 "F.CrtYd" user "Package Geometry/Place Bound Top")
		(29 "B.CrtYd" user "Package Geometry/Place Bound Bottom")
		(35 "F.Fab" user "Ref Des/Assembly Top")
		(33 "B.Fab" user "Ref Des/Assembly Bottom")
	)
	(footprint ""
		(layer "B.Cu")
		(at 52.891182 -72.842628 180)
		(property "Reference" "R781"
			(at 0 0 0)
			(layer "B.SilkS")
			(hide yes)
			(effects
				(font
					(size 1.27 1.27)
				)
				(justify mirror)
			)
		)
		(property "Value" ""
			(at 0 0 0)
			(layer "B.Fab")
			(effects
				(font
					(size 1.27 1.27)
				)
				(justify mirror)
			)
		)
		(duplicate_pad_numbers_are_jumpers no)
		(fp_line
			(start 0.7874 0.4064)
			(end 0.7874 -0.4064)
			(stroke
				(width 0.1524)
				(type default)
			)
			(layer "B.SilkS")
		)
		(fp_line
			(start 0.7874 -0.4064)
			(end -0.7874 -0.4064)
			(stroke
				(width 0.1524)
				(type default)
			)
			(layer "B.SilkS")
		)
		(fp_line
			(start -0.7874 0.4064)
			(end 0.7874 0.4064)
			(stroke
				(width 0.1524)
				(type default)
			)
			(layer "B.SilkS")
		)
		(fp_line
			(start -0.7874 -0.4064)
			(end -0.7874 0.4064)
			(stroke
				(width 0.1524)
				(type default)
			)
			(layer "B.SilkS")
		)
		(fp_line
			(start 0.67945 0.3048)
			(end 0.67945 -0.305054)
			(stroke
				(width 0.1)
				(type default)
			)
			(layer "B.Fab")
		)
		(fp_line
			(start 0.67945 -0.305054)
			(end 0.12065 -0.305054)
			(stroke
				(width 0.1)
				(type default)
			)
			(layer "B.Fab")
		)
		(fp_line
			(start 0.12065 0.3048)
			(end 0.67945 0.3048)
			(stroke
				(width 0.1)
				(type default)
			)
			(layer "B.Fab")
		)
		(fp_line
			(start 0.12065 0.2794)
			(end 0.12065 0.3048)
			(stroke
				(width 0.1)
				(type default)
			)
			(layer "B.Fab")
		)
		(fp_line
			(start 0.12065 -0.2794)
			(end -0.12065 -0.2794)
			(stroke
				(width 0.1)
				(type default)
			)
			(layer "B.Fab")
		)
		(fp_line
			(start 0.12065 -0.305054)
			(end 0.12065 -0.2794)
			(stroke
				(width 0.1)
				(type default)
			)
			(layer "B.Fab")
		)
		(fp_line
			(start -0.120396 0.3048)
			(end -0.120396 0.2794)
			(stroke
				(width 0.1)
				(type default)
			)
			(layer "B.Fab")
		)
		(fp_line
			(start -0.120396 0.2794)
			(end 0.12065 0.2794)
			(stroke
				(width 0.1)
				(type default)
			)
			(layer "B.Fab")
		)
		(fp_line
			(start -0.12065 -0.2794)
			(end -0.12065 -0.3048)
			(stroke
				(width 0.1)
				(type default)
			)
			(layer "B.Fab")
		)
		(fp_line
			(start -0.12065 -0.3048)
			(end -0.67945 -0.3048)
			(stroke
				(width 0.1)
				(type default)
			)
			(layer "B.Fab")
		)
		(fp_line
			(start -0.67945 0.3048)
			(end -0.120396 0.3048)
			(stroke
				(width 0.1)
				(type default)
			)
			(layer "B.Fab")
		)
		(fp_line
			(start -0.67945 -0.3048)
			(end -0.67945 0.3048)
			(stroke
				(width 0.1)
				(type default)
			)
			(layer "B.Fab")
		)
		(pad "1" smd circle
			(at 0.40005 0)
			(size 0 0)
			(layers "B.Cu" "B.Mask" "B.Paste")
			(net "P1V8_AUX")
		)
		(pad "2" smd circle
			(at -0.40005 0)
			(size 0 0)
			(layers "B.Cu" "B.Mask" "B.Paste")
			(net "ADCVREFEXT1")
		)
	)
	(footprint ""
		(layer "B.Cu")
		(at 56.6674 -63.7032 90)
		(property "Reference" "R239"
			(at 0 0 90)
			(layer "B.SilkS")
			(hide yes)
			(effects
				(font
					(size 1.27 1.27)
				)
				(justify mirror)
			)
		)
		(property "Value" ""
			(at 0 0 90)
			(layer "B.Fab")
			(effects
				(font
					(size 1.27 1.27)
				)
				(justify mirror)
			)
		)
		(duplicate_pad_numbers_are_jumpers no)
		(fp_line
			(start 0.7874 -0.4064)
			(end -0.7874 -0.4064)
			(stroke
				(width 0.1524)
				(type default)
			)
			(layer "B.SilkS")
		)
		(fp_line
			(start -0.7874 -0.4064)
			(end -0.7874 0.4064)
			(stroke
				(width 0.1524)
				(type default)
			)
			(layer "B.SilkS")
		)
		(fp_line
			(start 0.7874 0.4064)
			(end 0.7874 -0.4064)
			(stroke
				(width 0.1524)
				(type default)
			)
			(layer "B.SilkS")
		)
		(fp_line
			(start -0.7874 0.4064)
			(end 0.7874 0.4064)
			(stroke
				(width 0.1524)
				(type default)
			)
			(layer "B.SilkS")
		)
		(fp_line
			(start 0.67945 -0.305054)
			(end 0.12065 -0.305054)
			(stroke
				(width 0.1)
				(type default)
			)
			(layer "B.Fab")
		)
		(fp_line
			(start 0.12065 -0.305054)
			(end 0.12065 -0.2794)
			(stroke
				(width 0.1)
				(type default)
			)
			(layer "B.Fab")
		)
		(fp_line
			(start -0.12065 -0.3048)
			(end -0.67945 -0.3048)
			(stroke
				(width 0.1)
				(type default)
			)
			(layer "B.Fab")
		)
		(fp_line
			(start -0.67945 -0.3048)
			(end -0.67945 0.3048)
			(stroke
				(width 0.1)
				(type default)
			)
			(layer "B.Fab")
		)
		(fp_line
			(start 0.12065 -0.2794)
			(end -0.12065 -0.2794)
			(stroke
				(width 0.1)
				(type default)
			)
			(layer "B.Fab")
		)
		(fp_line
			(start -0.12065 -0.2794)
			(end -0.12065 -0.3048)
			(stroke
				(width 0.1)
				(type default)
			)
			(layer "B.Fab")
		)
		(fp_line
			(start 0.12065 0.2794)
			(end 0.12065 0.3048)
			(stroke
				(width 0.1)
				(type default)
			)
			(layer "B.Fab")
		)
		(fp_line
			(start -0.120396 0.2794)
			(end 0.12065 0.2794)
			(stroke
				(width 0.1)
				(type default)
			)
			(layer "B.Fab")
		)
		(fp_line
			(start 0.67945 0.3048)
			(end 0.67945 -0.305054)
			(stroke
				(width 0.1)
				(type default)
			)
			(layer "B.Fab")
		)
		(fp_line
			(start 0.12065 0.3048)
			(end 0.67945 0.3048)
			(stroke
				(width 0.1)
				(type default)
			)
			(layer "B.Fab")
		)
		(fp_line
			(start -0.120396 0.3048)
			(end -0.120396 0.2794)
			(stroke
				(width 0.1)
				(type default)
			)
			(layer "B.Fab")
		)
		(fp_line
			(start -0.67945 0.3048)
			(end -0.120396 0.3048)
			(stroke
				(width 0.1)
				(type default)
			)
			(layer "B.Fab")
		)
		(pad "1" smd circle
			(at 0.40005 0 270)
			(size 0 0)
			(layers "B.Cu" "B.Mask" "B.Paste")
			(net "P3V3_AUX")
		)
		(pad "2" smd circle
			(at -0.40005 0 270)
			(size 0 0)
			(layers "B.Cu" "B.Mask" "B.Paste")
			(net "PU_BMC_FWSPIABR_N")
		)
	)
	(footprint ""
		(layer "B.Cu")
		(at 38.0238 -46.25594 180)
		(property "Reference" "R428"
			(at 0 0 0)
			(layer "B.SilkS")
			(hide yes)
			(effects
				(font
					(size 1.27 1.27)
				)
				(justify mirror)
			)
		)
		(property "Value" ""
			(at 0 0 0)
			(layer "B.Fab")
			(effects
				(font
					(size 1.27 1.27)
				)
				(justify mirror)
			)
		)
		(duplicate_pad_numbers_are_jumpers no)
		(fp_line
			(start 0.7874 0.4064)
			(end 0.7874 -0.4064)
			(stroke
				(width 0.1524)
				(type default)
			)
			(layer "B.SilkS")
		)
		(fp_line
			(start 0.7874 -0.4064)
			(end -0.7874 -0.4064)
			(stroke
				(width 0.1524)
				(type default)
			)
			(layer "B.SilkS")
		)
		(fp_line
			(start -0.7874 0.4064)
			(end 0.7874 0.4064)
			(stroke
				(width 0.1524)
				(type default)
			)
			(layer "B.SilkS")
		)
		(fp_line
			(start -0.7874 -0.4064)
			(end -0.7874 0.4064)
			(stroke
				(width 0.1524)
				(type default)
			)
			(layer "B.SilkS")
		)
		(fp_line
			(start 0.67945 0.3048)
			(end 0.67945 -0.305054)
			(stroke
				(width 0.1)
				(type default)
			)
			(layer "B.Fab")
		)
		(fp_line
			(start 0.67945 -0.305054)
			(end 0.12065 -0.305054)
			(stroke
				(width 0.1)
				(type default)
			)
			(layer "B.Fab")
		)
		(fp_line
			(start 0.12065 0.3048)
			(end 0.67945 0.3048)
			(stroke
				(width 0.1)
				(type default)
			)
			(layer "B.Fab")
		)
		(fp_line
			(start 0.12065 0.2794)
			(end 0.12065 0.3048)
			(stroke
				(width 0.1)
				(type default)
			)
			(layer "B.Fab")
		)
		(fp_line
			(start 0.12065 -0.2794)
			(end -0.12065 -0.2794)
			(stroke
				(width 0.1)
				(type default)
			)
			(layer "B.Fab")
		)
		(fp_line
			(start 0.12065 -0.305054)
			(end 0.12065 -0.2794)
			(stroke
				(width 0.1)
				(type default)
			)
			(layer "B.Fab")
		)
		(fp_line
			(start -0.120396 0.3048)
			(end -0.120396 0.2794)
			(stroke
				(width 0.1)
				(type default)
			)
			(layer "B.Fab")
		)
		(fp_line
			(start -0.120396 0.2794)
			(end 0.12065 0.2794)
			(stroke
				(width 0.1)
				(type default)
			)
			(layer "B.Fab")
		)
		(fp_line
			(start -0.12065 -0.2794)
			(end -0.12065 -0.3048)
			(stroke
				(width 0.1)
				(type default)
			)
			(layer "B.Fab")
		)
		(fp_line
			(start -0.12065 -0.3048)
			(end -0.67945 -0.3048)
			(stroke
				(width 0.1)
				(type default)
			)
			(layer "B.Fab")
		)
		(fp_line
			(start -0.67945 0.3048)
			(end -0.120396 0.3048)
			(stroke
				(width 0.1)
				(type default)
			)
			(layer "B.Fab")
		)
		(fp_line
			(start -0.67945 -0.3048)
			(end -0.67945 0.3048)
			(stroke
				(width 0.1)
				(type default)
			)
			(layer "B.Fab")
		)
		(pad "1" smd circle
			(at 0.40005 0)
			(size 0 0)
			(layers "B.Cu" "B.Mask" "B.Paste")
			(net "P3V3_AUX")
		)
		(pad "2" smd circle
			(at -0.40005 0)
			(size 0 0)
			(layers "B.Cu" "B.Mask" "B.Paste")
			(net "SMB_BMC_MM13_SDA")
		)
	)
	(footprint ""
		(layer "B.Cu")
		(at 13.2588 -83.693 90)
		(property "Reference" "R690"
			(at 0 0 90)
			(layer "B.SilkS")
			(hide yes)
			(effects
				(font
					(size 1.27 1.27)
				)
				(justify mirror)
			)
		)
		(property "Value" ""
			(at 0 0 90)
			(layer "B.Fab")
			(effects
				(font
					(size 1.27 1.27)
				)
				(justify mirror)
			)
		)
		(duplicate_pad_numbers_are_jumpers no)
		(fp_line
			(start 0.7874 -0.4064)
			(end -0.7874 -0.4064)
			(stroke
				(width 0.1524)
				(type default)
			)
			(layer "B.SilkS")
		)
		(fp_line
			(start -0.7874 -0.4064)
			(end -0.7874 0.4064)
			(stroke
				(width 0.1524)
				(type default)
			)
			(layer "B.SilkS")
		)
		(fp_line
			(start 0.7874 0.4064)
			(end 0.7874 -0.4064)
			(stroke
				(width 0.1524)
				(type default)
			)
			(layer "B.SilkS")
		)
		(fp_line
			(start -0.7874 0.4064)
			(end 0.7874 0.4064)
			(stroke
				(width 0.1524)
				(type default)
			)
			(layer "B.SilkS")
		)
		(fp_line
			(start 0.67945 -0.305054)
			(end 0.12065 -0.305054)
			(stroke
				(width 0.1)
				(type default)
			)
			(layer "B.Fab")
		)
		(fp_line
			(start 0.12065 -0.305054)
			(end 0.12065 -0.2794)
			(stroke
				(width 0.1)
				(type default)
			)
			(layer "B.Fab")
		)
		(fp_line
			(start -0.12065 -0.3048)
			(end -0.67945 -0.3048)
			(stroke
				(width 0.1)
				(type default)
			)
			(layer "B.Fab")
		)
		(fp_line
			(start -0.67945 -0.3048)
			(end -0.67945 0.3048)
			(stroke
				(width 0.1)
				(type default)
			)
			(layer "B.Fab")
		)
		(fp_line
			(start 0.12065 -0.2794)
			(end -0.12065 -0.2794)
			(stroke
				(width 0.1)
				(type default)
			)
			(layer "B.Fab")
		)
		(fp_line
			(start -0.12065 -0.2794)
			(end -0.12065 -0.3048)
			(stroke
				(width 0.1)
				(type default)
			)
			(layer "B.Fab")
		)
		(fp_line
			(start 0.12065 0.2794)
			(end 0.12065 0.3048)
			(stroke
				(width 0.1)
				(type default)
			)
			(layer "B.Fab")
		)
		(fp_line
			(start -0.120396 0.2794)
			(end 0.12065 0.2794)
			(stroke
				(width 0.1)
				(type default)
			)
			(layer "B.Fab")
		)
		(fp_line
			(start 0.67945 0.3048)
			(end 0.67945 -0.305054)
			(stroke
				(width 0.1)
				(type default)
			)
			(layer "B.Fab")
		)
		(fp_line
			(start 0.12065 0.3048)
			(end 0.67945 0.3048)
			(stroke
				(width 0.1)
				(type default)
			)
			(layer "B.Fab")
		)
		(fp_line
			(start -0.120396 0.3048)
			(end -0.120396 0.2794)
			(stroke
				(width 0.1)
				(type default)
			)
			(layer "B.Fab")
		)
		(fp_line
			(start -0.67945 0.3048)
			(end -0.120396 0.3048)
			(stroke
				(width 0.1)
				(type default)
			)
			(layer "B.Fab")
		)
		(pad "1" smd circle
			(at 0.40005 0 270)
			(size 0 0)
			(layers "B.Cu" "B.Mask" "B.Paste")
			(net "IRQ_SGPIO_R_N")
		)
		(pad "2" smd circle
			(at -0.40005 0 270)
			(size 0 0)
			(layers "B.Cu" "B.Mask" "B.Paste")
			(net "IRQ_SGPIO_N")
		)
	)
	(footprint ""
		(layer "B.Cu")
		(at 74.715878 -96.50984 90)
		(property "Reference" "Q7"
			(at 2.24409 0.315722 0)
			(unlocked yes)
			(layer "B.SilkS")
			(effects
				(font
					(size 0.7874 0.5842)
					(thickness 0.1524)
				)
				(justify left mirror)
			)
		)
		(property "Value" ""
			(at 0 0 90)
			(layer "B.Fab")
			(effects
				(font
					(size 1.27 1.27)
				)
				(justify mirror)
			)
		)
		(duplicate_pad_numbers_are_jumpers no)
		(fp_line
			(start 1.603248 -1.500124)
			(end -1.603248 -1.500124)
			(stroke
				(width 0.1524)
				(type default)
			)
			(layer "B.SilkS")
		)
		(fp_line
			(start -1.603248 -1.500124)
			(end -1.603248 1.500124)
			(stroke
				(width 0.1524)
				(type default)
			)
			(layer "B.SilkS")
		)
		(fp_line
			(start 1.603248 1.500124)
			(end 1.603248 -1.500124)
			(stroke
				(width 0.1524)
				(type default)
			)
			(layer "B.SilkS")
		)
		(fp_line
			(start -1.603248 1.500124)
			(end 1.603248 1.500124)
			(stroke
				(width 0.1524)
				(type default)
			)
			(layer "B.SilkS")
		)
		(fp_line
			(start 0.700024 -1.500124)
			(end 0.700024 -1.169924)
			(stroke
				(width 0.1)
				(type default)
			)
			(layer "B.Fab")
		)
		(fp_line
			(start -0.700024 -1.500124)
			(end 0.700024 -1.500124)
			(stroke
				(width 0.1)
				(type default)
			)
			(layer "B.Fab")
		)
		(fp_line
			(start 1.249934 -1.169924)
			(end 1.249934 -0.729996)
			(stroke
				(width 0.1)
				(type default)
			)
			(layer "B.Fab")
		)
		(fp_line
			(start 0.700024 -1.169924)
			(end 1.249934 -1.169924)
			(stroke
				(width 0.1)
				(type default)
			)
			(layer "B.Fab")
		)
		(fp_line
			(start 1.249934 -0.729996)
			(end 0.6985 -0.729996)
			(stroke
				(width 0.1)
				(type default)
			)
			(layer "B.Fab")
		)
		(fp_line
			(start 0.6985 -0.729996)
			(end 0.6985 0.729996)
			(stroke
				(width 0.1)
				(type default)
			)
			(layer "B.Fab")
		)
		(fp_line
			(start -0.700024 -0.219964)
			(end -0.700024 -1.500124)
			(stroke
				(width 0.1)
				(type default)
			)
			(layer "B.Fab")
		)
		(fp_line
			(start -1.249934 -0.219964)
			(end -0.700024 -0.219964)
			(stroke
				(width 0.1)
				(type default)
			)
			(layer "B.Fab")
		)
		(fp_line
			(start -0.700024 0.219964)
			(end -1.249934 0.219964)
			(stroke
				(width 0.1)
				(type default)
			)
			(layer "B.Fab")
		)
		(fp_line
			(start -1.249934 0.219964)
			(end -1.249934 -0.219964)
			(stroke
				(width 0.1)
				(type default)
			)
			(layer "B.Fab")
		)
		(fp_line
			(start 1.249934 0.729996)
			(end 1.249934 1.169924)
			(stroke
				(width 0.1)
				(type default)
			)
			(layer "B.Fab")
		)
		(fp_line
			(start 0.6985 0.729996)
			(end 1.249934 0.729996)
			(stroke
				(width 0.1)
				(type default)
			)
			(layer "B.Fab")
		)
		(fp_line
			(start 1.249934 1.169924)
			(end 0.700024 1.169924)
			(stroke
				(width 0.1)
				(type default)
			)
			(layer "B.Fab")
		)
		(fp_line
			(start 0.700024 1.169924)
			(end 0.700024 1.500124)
			(stroke
				(width 0.1)
				(type default)
			)
			(layer "B.Fab")
		)
		(fp_line
			(start 0.700024 1.500124)
			(end -0.700024 1.500124)
			(stroke
				(width 0.1)
				(type default)
			)
			(layer "B.Fab")
		)
		(fp_line
			(start -0.700024 1.500124)
			(end -0.700024 0.219964)
			(stroke
				(width 0.1)
				(type default)
			)
			(layer "B.Fab")
		)
		(fp_rect
			(start 0.700024 1.500124)
			(end -0.700024 -1.500124)
			(stroke
				(width 0)
				(type default)
			)
			(fill no)
			(layer "B.Fab")
		)
		(pad "D" smd rect
			(at -0.999998 0)
			(size 0.8128 0.9144)
			(layers "B.Cu" "B.Mask" "B.Paste")
			(net "Q7_D")
		)
		(pad "G" smd rect
			(at 0.999998 -0.94996)
			(size 0.8128 0.9144)
			(layers "B.Cu" "B.Mask" "B.Paste")
			(net "LPC_ESPI_SEL_R1")
		)
		(pad "S" smd rect
			(at 0.999998 0.94996)
			(size 0.8128 0.9144)
			(layers "B.Cu" "B.Mask" "B.Paste")
			(net "SPI_BMC_TPM_MOSI")
		)
	)
	(footprint ""
		(layer "B.Cu")
		(at 49.5046 -53.2638 180)
		(property "Reference" "C139"
			(at 0 0 0)
			(layer "B.SilkS")
			(hide yes)
			(effects
				(font
					(size 1.27 1.27)
				)
				(justify mirror)
			)
		)
		(property "Value" ""
			(at 0 0 0)
			(layer "B.Fab")
			(effects
				(font
					(size 1.27 1.27)
				)
				(justify mirror)
			)
		)
		(duplicate_pad_numbers_are_jumpers no)
		(fp_line
			(start 0.7874 0.4064)
			(end 0.7874 -0.4064)
			(stroke
				(width 0.1524)
				(type default)
			)
			(layer "B.SilkS")
		)
		(fp_line
			(start 0.7874 -0.4064)
			(end -0.7874 -0.4064)
			(stroke
				(width 0.1524)
				(type default)
			)
			(layer "B.SilkS")
		)
		(fp_line
			(start -0.7874 0.4064)
			(end 0.7874 0.4064)
			(stroke
				(width 0.1524)
				(type default)
			)
			(layer "B.SilkS")
		)
		(fp_line
			(start -0.7874 -0.4064)
			(end -0.7874 0.4064)
			(stroke
				(width 0.1524)
				(type default)
			)
			(layer "B.SilkS")
		)
		(fp_line
			(start 0.67945 0.3048)
			(end 0.67945 -0.305054)
			(stroke
				(width 0.1)
				(type default)
			)
			(layer "B.Fab")
		)
		(fp_line
			(start 0.67945 -0.305054)
			(end 0.12065 -0.305054)
			(stroke
				(width 0.1)
				(type default)
			)
			(layer "B.Fab")
		)
		(fp_line
			(start 0.12065 0.3048)
			(end 0.67945 0.3048)
			(stroke
				(width 0.1)
				(type default)
			)
			(layer "B.Fab")
		)
		(fp_line
			(start 0.12065 0.2794)
			(end 0.12065 0.3048)
			(stroke
				(width 0.1)
				(type default)
			)
			(layer "B.Fab")
		)
		(fp_line
			(start 0.12065 -0.2794)
			(end -0.12065 -0.2794)
			(stroke
				(width 0.1)
				(type default)
			)
			(layer "B.Fab")
		)
		(fp_line
			(start 0.12065 -0.305054)
			(end 0.12065 -0.2794)
			(stroke
				(width 0.1)
				(type default)
			)
			(layer "B.Fab")
		)
		(fp_line
			(start -0.120396 0.3048)
			(end -0.120396 0.2794)
			(stroke
				(width 0.1)
				(type default)
			)
			(layer "B.Fab")
		)
		(fp_line
			(start -0.120396 0.2794)
			(end 0.12065 0.2794)
			(stroke
				(width 0.1)
				(type default)
			)
			(layer "B.Fab")
		)
		(fp_line
			(start -0.12065 -0.2794)
			(end -0.12065 -0.3048)
			(stroke
				(width 0.1)
				(type default)
			)
			(layer "B.Fab")
		)
		(fp_line
			(start -0.12065 -0.3048)
			(end -0.67945 -0.3048)
			(stroke
				(width 0.1)
				(type default)
			)
			(layer "B.Fab")
		)
		(fp_line
			(start -0.67945 0.3048)
			(end -0.120396 0.3048)
			(stroke
				(width 0.1)
				(type default)
			)
			(layer "B.Fab")
		)
		(fp_line
			(start -0.67945 -0.3048)
			(end -0.67945 0.3048)
			(stroke
				(width 0.1)
				(type default)
			)
			(layer "B.Fab")
		)
		(pad "1" smd circle
			(at 0.40005 0)
			(size 0 0)
			(layers "B.Cu" "B.Mask" "B.Paste")
			(net "P1V2_P1V0_I3C_VDDL1")
		)
		(pad "2" smd circle
			(at -0.40005 0)
			(size 0 0)
			(layers "B.Cu" "B.Mask" "B.Paste")
			(net "GND")
		)
	)
)
